(kicad_pcb
	(version 20260206)
	(generator "pcbnew")
	(generator_version "10.0")
	(general
		(thickness 1.6)
		(legacy_teardrops no)
	)
	(paper "A4")
	(title_block
		(title "03242023_DA0F0TMBIJ0_F0T_Motherboard_J_brd_V01_OCP.brd")
		(comment 1 "Grand Teton / footprints 355-359 of 6105")
	)
	(layers
		(0 "F.Cu" signal "TOP")
		(4 "In1.Cu" signal "GND")
		(6 "In2.Cu" signal "IN1")
		(8 "In3.Cu" signal "GND1")
		(10 "In4.Cu" signal "IN2")
		(12 "In5.Cu" signal "GND2")
		(14 "In6.Cu" signal "IN3")
		(16 "In7.Cu" signal "GND3")
		(18 "In8.Cu" signal "VCC")
		(20 "In9.Cu" signal "VCC1")
		(22 "In10.Cu" signal "GND4")
		(24 "In11.Cu" signal "IN4")
		(26 "In12.Cu" signal "GND5")
		(28 "In13.Cu" signal "IN5")
		(30 "In14.Cu" signal "GND6")
		(32 "In15.Cu" signal "IN6")
		(34 "In16.Cu" signal "GND7")
		(2 "B.Cu" signal "BOTTOM")
		(9 "F.Adhes" user "F.Adhesive")
		(11 "B.Adhes" user "B.Adhesive")
		(13 "F.Paste" user "Package Geometry/Pastemask Top")
		(15 "B.Paste" user "Package Geometry/Pastemask Bottom")
		(5 "F.SilkS" user "Ref Des/Silkscreen Top")
		(7 "B.SilkS" user "Ref Des/Silkscreen Bottom")
		(1 "F.Mask" user "Board Geometry/Soldermask Top")
		(3 "B.Mask" user "Board Geometry/Soldermask Bottom")
		(17 "Dwgs.User" user "User.Drawings")
		(19 "Cmts.User" user "User.Comments")
		(21 "Eco1.User" user "User.Eco1")
		(23 "Eco2.User" user "User.Eco2")
		(25 "Edge.Cuts" user "Board Geometry/Outline")
		(27 "Margin" user)
		(31 "F.CrtYd" user "Package Geometry/Place Bound Top")
		(29 "B.CrtYd" user "Package Geometry/Place Bound Bottom")
		(35 "F.Fab" user "Ref Des/Assembly Top")
		(33 "B.Fab" user "Ref Des/Assembly Bottom")
	)
	(footprint ""
		(layer "F.Cu")
		(at 140.208 -368.645948 -90)
		(property "Reference" "R1713"
			(at 0 0 270)
			(layer "F.SilkS")
			(hide yes)
			(effects
				(font
					(size 1.27 1.27)
				)
			)
		)
		(property "Value" ""
			(at 0 0 270)
			(layer "F.Fab")
			(effects
				(font
					(size 1.27 1.27)
				)
			)
		)
		(duplicate_pad_numbers_are_jumpers no)
		(fp_line
			(start -0.7874 0.4064)
			(end -0.7874 -0.4064)
			(stroke
				(width 0.1524)
				(type default)
			)
			(layer "F.SilkS")
		)
		(fp_line
			(start 0.7874 0.4064)
			(end -0.7874 0.4064)
			(stroke
				(width 0.1524)
				(type default)
			)
			(layer "F.SilkS")
		)
		(fp_line
			(start -0.7874 -0.4064)
			(end 0.7874 -0.4064)
			(stroke
				(width 0.1524)
				(type default)
			)
			(layer "F.SilkS")
		)
		(fp_line
			(start 0.7874 -0.4064)
			(end 0.7874 0.4064)
			(stroke
				(width 0.1524)
				(type default)
			)
			(layer "F.SilkS")
		)
		(fp_line
			(start -0.67945 0.3048)
			(end -0.67945 -0.305054)
			(stroke
				(width 0.1)
				(type default)
			)
			(layer "F.Fab")
		)
		(fp_line
			(start -0.12065 0.3048)
			(end -0.67945 0.3048)
			(stroke
				(width 0.1)
				(type default)
			)
			(layer "F.Fab")
		)
		(fp_line
			(start 0.120396 0.3048)
			(end 0.120396 0.2794)
			(stroke
				(width 0.1)
				(type default)
			)
			(layer "F.Fab")
		)
		(fp_line
			(start 0.67945 0.3048)
			(end 0.120396 0.3048)
			(stroke
				(width 0.1)
				(type default)
			)
			(layer "F.Fab")
		)
		(fp_line
			(start -0.12065 0.2794)
			(end -0.12065 0.3048)
			(stroke
				(width 0.1)
				(type default)
			)
			(layer "F.Fab")
		)
		(fp_line
			(start 0.120396 0.2794)
			(end -0.12065 0.2794)
			(stroke
				(width 0.1)
				(type default)
			)
			(layer "F.Fab")
		)
		(fp_line
			(start -0.12065 -0.2794)
			(end 0.12065 -0.2794)
			(stroke
				(width 0.1)
				(type default)
			)
			(layer "F.Fab")
		)
		(fp_line
			(start 0.12065 -0.2794)
			(end 0.12065 -0.3048)
			(stroke
				(width 0.1)
				(type default)
			)
			(layer "F.Fab")
		)
		(fp_line
			(start 0.12065 -0.3048)
			(end 0.67945 -0.3048)
			(stroke
				(width 0.1)
				(type default)
			)
			(layer "F.Fab")
		)
		(fp_line
			(start 0.67945 -0.3048)
			(end 0.67945 0.3048)
			(stroke
				(width 0.1)
				(type default)
			)
			(layer "F.Fab")
		)
		(fp_line
			(start -0.67945 -0.305054)
			(end -0.12065 -0.305054)
			(stroke
				(width 0.1)
				(type default)
			)
			(layer "F.Fab")
		)
		(fp_line
			(start -0.12065 -0.305054)
			(end -0.12065 -0.2794)
			(stroke
				(width 0.1)
				(type default)
			)
			(layer "F.Fab")
		)
		(pad "1" smd circle
			(at -0.40005 0 270)
			(size 0 0)
			(layers "F.Cu" "F.Mask" "F.Paste")
			(net "SMB_VR_3V3AUX_SCL_R3")
		)
		(pad "2" smd circle
			(at 0.40005 0 270)
			(size 0 0)
			(layers "F.Cu" "F.Mask" "F.Paste")
			(net "P3V3_AUX")
		)
	)
	(footprint ""
		(layer "F.Cu")
		(at 164.64788 -113.756948)
		(property "Reference" "R3485"
			(at 0 0 0)
			(layer "F.SilkS")
			(hide yes)
			(effects
				(font
					(size 1.27 1.27)
				)
			)
		)
		(property "Value" ""
			(at 0 0 0)
			(layer "F.Fab")
			(effects
				(font
					(size 1.27 1.27)
				)
			)
		)
		(duplicate_pad_numbers_are_jumpers no)
		(fp_line
			(start -0.7874 -0.4064)
			(end 0.7874 -0.4064)
			(stroke
				(width 0.1524)
				(type default)
			)
			(layer "F.SilkS")
		)
		(fp_line
			(start -0.7874 0.4064)
			(end -0.7874 -0.4064)
			(stroke
				(width 0.1524)
				(type default)
			)
			(layer "F.SilkS")
		)
		(fp_line
			(start 0.7874 -0.4064)
			(end 0.7874 0.4064)
			(stroke
				(width 0.1524)
				(type default)
			)
			(layer "F.SilkS")
		)
		(fp_line
			(start 0.7874 0.4064)
			(end -0.7874 0.4064)
			(stroke
				(width 0.1524)
				(type default)
			)
			(layer "F.SilkS")
		)
		(fp_line
			(start -0.67945 -0.305054)
			(end -0.12065 -0.305054)
			(stroke
				(width 0.1)
				(type default)
			)
			(layer "F.Fab")
		)
		(fp_line
			(start -0.67945 0.3048)
			(end -0.67945 -0.305054)
			(stroke
				(width 0.1)
				(type default)
			)
			(layer "F.Fab")
		)
		(fp_line
			(start -0.12065 -0.305054)
			(end -0.12065 -0.2794)
			(stroke
				(width 0.1)
				(type default)
			)
			(layer "F.Fab")
		)
		(fp_line
			(start -0.12065 -0.2794)
			(end 0.12065 -0.2794)
			(stroke
				(width 0.1)
				(type default)
			)
			(layer "F.Fab")
		)
		(fp_line
			(start -0.12065 0.2794)
			(end -0.12065 0.3048)
			(stroke
				(width 0.1)
				(type default)
			)
			(layer "F.Fab")
		)
		(fp_line
			(start -0.12065 0.3048)
			(end -0.67945 0.3048)
			(stroke
				(width 0.1)
				(type default)
			)
			(layer "F.Fab")
		)
		(fp_line
			(start 0.120396 0.2794)
			(end -0.12065 0.2794)
			(stroke
				(width 0.1)
				(type default)
			)
			(layer "F.Fab")
		)
		(fp_line
			(start 0.120396 0.3048)
			(end 0.120396 0.2794)
			(stroke
				(width 0.1)
				(type default)
			)
			(layer "F.Fab")
		)
		(fp_line
			(start 0.12065 -0.3048)
			(end 0.67945 -0.3048)
			(stroke
				(width 0.1)
				(type default)
			)
			(layer "F.Fab")
		)
		(fp_line
			(start 0.12065 -0.2794)
			(end 0.12065 -0.3048)
			(stroke
				(width 0.1)
				(type default)
			)
			(layer "F.Fab")
		)
		(fp_line
			(start 0.67945 -0.3048)
			(end 0.67945 0.3048)
			(stroke
				(width 0.1)
				(type default)
			)
			(layer "F.Fab")
		)
		(fp_line
			(start 0.67945 0.3048)
			(end 0.120396 0.3048)
			(stroke
				(width 0.1)
				(type default)
			)
			(layer "F.Fab")
		)
		(pad "1" smd circle
			(at -0.40005 0)
			(size 0 0)
			(layers "F.Cu" "F.Mask" "F.Paste")
			(net "GPU_WP_HW_CTRL_N")
		)
		(pad "2" smd circle
			(at 0.40005 0)
			(size 0 0)
			(layers "F.Cu" "F.Mask" "F.Paste")
			(net "GPU_WP_HW_CTRL_R_N")
		)
	)
	(footprint ""
		(layer "F.Cu")
		(at 156.085794 -408.517344 -90)
		(property "Reference" "C1539"
			(at 0 0 270)
			(layer "F.SilkS")
			(hide yes)
			(effects
				(font
					(size 1.27 1.27)
				)
			)
		)
		(property "Value" ""
			(at 0 0 270)
			(layer "F.Fab")
			(effects
				(font
					(size 1.27 1.27)
				)
			)
		)
		(duplicate_pad_numbers_are_jumpers no)
		(fp_line
			(start -0.299974 0.150114)
			(end -0.299974 -0.150114)
			(stroke
				(width 0.1)
				(type default)
			)
			(layer "F.Fab")
		)
		(fp_line
			(start 0.299974 0.150114)
			(end -0.299974 0.150114)
			(stroke
				(width 0.1)
				(type default)
			)
			(layer "F.Fab")
		)
		(fp_line
			(start -0.299974 -0.150114)
			(end 0.299974 -0.150114)
			(stroke
				(width 0.1)
				(type default)
			)
			(layer "F.Fab")
		)
		(fp_line
			(start 0.299974 -0.150114)
			(end 0.299974 0.150114)
			(stroke
				(width 0.1)
				(type default)
			)
			(layer "F.Fab")
		)
		(pad "1" smd rect
			(at -0.2667 0 270)
			(size 0.3048 0.381)
			(layers "F.Cu" "F.Mask" "F.Paste")
			(net "P5E_CPU1_PE3_TX_C_DP<4>")
		)
		(pad "2" smd rect
			(at 0.2667 0 270)
			(size 0.3048 0.381)
			(layers "F.Cu" "F.Mask" "F.Paste")
			(net "P5E_CPU1_PE3_TX_DP<4>")
		)
	)
	(footprint ""
		(layer "F.Cu")
		(at 113.318798 -333.716122)
		(property "Reference" "PU28_P1_3"
			(at -1.810258 -6.183376 0)
			(unlocked yes)
			(layer "F.SilkS")
			(effects
				(font
					(size 0.7874 0.5842)
					(thickness 0.1524)
				)
				(justify left)
			)
		)
		(property "Value" ""
			(at 0 0 0)
			(layer "F.Fab")
			(effects
				(font
					(size 1.27 1.27)
				)
			)
		)
		(duplicate_pad_numbers_are_jumpers no)
		(fp_line
			(start -2.500122 -2.999994)
			(end -2.24409 -2.999994)
			(stroke
				(width 0.1524)
				(type default)
			)
			(layer "F.SilkS")
		)
		(fp_line
			(start -2.500122 -2.529078)
			(end -2.500122 -2.999994)
			(stroke
				(width 0.1524)
				(type default)
			)
			(layer "F.SilkS")
		)
		(fp_line
			(start -2.500122 0.6604)
			(end -2.500122 0.229108)
			(stroke
				(width 0.1524)
				(type default)
			)
			(layer "F.SilkS")
		)
		(fp_line
			(start -2.500122 2.999994)
			(end -2.500122 2.339594)
			(stroke
				(width 0.1524)
				(type default)
			)
			(layer "F.SilkS")
		)
		(fp_line
			(start -2.2987 2.999994)
			(end -2.500122 2.999994)
			(stroke
				(width 0.1524)
				(type default)
			)
			(layer "F.SilkS")
		)
		(fp_line
			(start 2.31394 -2.999994)
			(end 2.500122 -2.999994)
			(stroke
				(width 0.1524)
				(type default)
			)
			(layer "F.SilkS")
		)
		(fp_line
			(start 2.500122 -2.999994)
			(end 2.500122 -2.44348)
			(stroke
				(width 0.1524)
				(type default)
			)
			(layer "F.SilkS")
		)
		(fp_line
			(start 2.500122 2.339594)
			(end 2.500122 2.999994)
			(stroke
				(width 0.1524)
				(type default)
			)
			(layer "F.SilkS")
		)
		(fp_line
			(start 2.500122 2.999994)
			(end 2.2987 2.999994)
			(stroke
				(width 0.1524)
				(type default)
			)
			(layer "F.SilkS")
		)
		(fp_poly
			(pts
				(xy -2.148586 -3.63728) (xy -2.656586 -2.62128) (xy -3.164586 -3.63728)
			)
			(stroke
				(width 0)
				(type default)
			)
			(fill yes)
			(layer "F.SilkS")
		)
		(fp_line
			(start -2.500122 -2.999994)
			(end 2.500122 -2.999994)
			(stroke
				(width 0.1)
				(type default)
			)
			(layer "F.Fab")
		)
		(fp_line
			(start -2.500122 2.999994)
			(end -2.500122 -2.999994)
			(stroke
				(width 0.1)
				(type default)
			)
			(layer "F.Fab")
		)
		(fp_line
			(start 2.500122 -2.999994)
			(end 2.500122 2.999994)
			(stroke
				(width 0.1)
				(type default)
			)
			(layer "F.Fab")
		)
		(fp_line
			(start 2.500122 2.999994)
			(end -2.500122 2.999994)
			(stroke
				(width 0.1)
				(type default)
			)
			(layer "F.Fab")
		)
		(fp_poly
			(pts
				(xy -4.218432 -2.783078) (xy -4.218432 -1.767078) (xy -3.202432 -2.275078)
			)
			(stroke
				(width 0)
				(type default)
			)
			(fill yes)
			(layer "F.Fab")
		)
		(pad "1" smd rect
			(at -2.400046 -2.275078 90)
			(size 0.2286 0.6096)
			(layers "F.Cu" "F.Mask" "F.Paste")
			(net "PVCCIN_CPU1_VOS3")
		)
		(pad "2" smd rect
			(at -2.400046 -1.82499 90)
			(size 0.2286 0.6096)
			(layers "F.Cu" "F.Mask" "F.Paste")
			(net "GND")
		)
		(pad "3" smd rect
			(at -2.400046 -1.374902 90)
			(size 0.2286 0.6096)
			(layers "F.Cu" "F.Mask" "F.Paste")
			(net "PVCCIN_CPU1_VDD3")
		)
		(pad "4" smd rect
			(at -2.400046 -0.925068 90)
			(size 0.2286 0.6096)
			(layers "F.Cu" "F.Mask" "F.Paste")
			(net "PVCCIN_CPU1_PVCC")
		)
		(pad "5" smd rect
			(at -2.400046 -0.47498 90)
			(size 0.2286 0.6096)
			(layers "F.Cu" "F.Mask" "F.Paste")
			(net "GND")
		)
		(pad "6" smd rect
			(at -2.400046 -0.024892 90)
			(size 0.2286 0.6096)
			(layers "F.Cu" "F.Mask" "F.Paste")
			(net "Net_8526")
		)
		(pad "7_9-20_24" smd circle
			(at 0 1.150112 90)
			(size 0 0)
			(layers "F.Cu" "F.Mask" "F.Paste")
			(net "GND")
		)
		(pad "10_19" smd rect
			(at 0 2.899918 90)
			(size 0.6096 4.318)
			(layers "F.Cu" "F.Mask" "F.Paste")
			(net "SW_PVCCIN_CPU1_SW3")
		)
		(pad "25_29" smd rect
			(at 1.549908 -1.279906 270)
			(size 2.0574 2.3114)
			(layers "F.Cu" "F.Mask" "F.Paste")
			(net "SW_P12V_PVCCIN_CPU1_FLT")
		)
		(pad "30" smd rect
			(at 2.05994 -2.899918)
			(size 0.2286 0.6096)
			(layers "F.Cu" "F.Mask" "F.Paste")
			(net "SW_P12V_PVCCIN_CPU1_FLT")
		)
		(pad "31" smd rect
			(at 1.610106 -2.899918)
			(size 0.2286 0.6096)
			(layers "F.Cu" "F.Mask" "F.Paste")
			(net "Net_8527")
		)
		(pad "32" smd rect
			(at 1.160018 -2.899918)
			(size 0.2286 0.6096)
			(layers "F.Cu" "F.Mask" "F.Paste")
			(net "SW_PVCCIN_CPU1_BOOTR3")
		)
		(pad "33" smd rect
			(at 0.70993 -2.899918)
			(size 0.2286 0.6096)
			(layers "F.Cu" "F.Mask" "F.Paste")
			(net "SW_PVCCIN_CPU1_BOOT3")
		)
		(pad "34" smd rect
			(at 0.260096 -2.899918)
			(size 0.2286 0.6096)
			(layers "F.Cu" "F.Mask" "F.Paste")
			(net "PVCCIN_CPU1_PWM3")
		)
		(pad "35" smd rect
			(at -0.189992 -2.899918)
			(size 0.2286 0.6096)
			(layers "F.Cu" "F.Mask" "F.Paste")
			(net "PVCCIN_CPU1_VDD3")
		)
		(pad "36" smd rect
			(at -0.64008 -2.899918)
			(size 0.2286 0.6096)
			(layers "F.Cu" "F.Mask" "F.Paste")
			(net "PVCCIN_CPU1_ATSEN")
		)
		(pad "37" smd rect
			(at -1.089914 -2.899918)
			(size 0.2286 0.6096)
			(layers "F.Cu" "F.Mask" "F.Paste")
			(net "PVCCIN_CPU1_LSET3")
		)
		(pad "38" smd rect
			(at -1.540002 -2.899918)
			(size 0.2286 0.6096)
			(layers "F.Cu" "F.Mask" "F.Paste")
			(net "PVCCIN_CPU1_IMON3")
		)
		(pad "39" smd rect
			(at -1.99009 -2.899918)
			(size 0.2286 0.6096)
			(layers "F.Cu" "F.Mask" "F.Paste")
			(net "PVCCIN_CPU1_VREF")
		)
		(pad "40" smd rect
			(at -0.87503 -1.27508)
			(size 1.7526 1.9558)
			(layers "F.Cu" "F.Mask" "F.Paste")
			(net "GND")
		)
		(pad "41" smd rect
			(at -1.525016 0.249936 270)
			(size 0.3048 0.4572)
			(layers "F.Cu" "F.Mask" "F.Paste")
			(net "Net_8525")
		)
		(zone
			(layer "F.Cu")
			(hatch none 0.5)
			(connect_pads
				(clearance 0)
			)
			(min_thickness 0.25)
			(keepout
				(tracks not_allowed)
				(vias allowed)
				(pads allowed)
				(copperpour not_allowed)
				(footprints allowed)
			)
			(placement
				(enabled no)
				(sheetname "")
			)
			(fill
				(thermal_gap 0.5)
				(thermal_bridge_width 0.5)
				(island_removal_mode 0)
			)
			(polygon
				(pts
					(xy 110.818676 -330.716128) (xy 110.818676 -331.465428) (xy 115.81892 -331.465428) (xy 115.81892 -330.716128)
					(xy 115.528598 -330.716128) (xy 115.528598 -331.171804) (xy 111.108998 -331.171804) (xy 111.108998 -330.716128)
				)
			)
		)
		(zone
			(layer "F.Cu")
			(hatch none 0.5)
			(connect_pads
				(clearance 0)
			)
			(min_thickness 0.25)
			(keepout
				(tracks not_allowed)
				(vias allowed)
				(pads allowed)
				(copperpour not_allowed)
				(footprints allowed)
			)
			(placement
				(enabled no)
				(sheetname "")
			)
			(fill
				(thermal_gap 0.5)
				(thermal_bridge_width 0.5)
				(island_removal_mode 0)
			)
			(polygon
				(pts
					(xy 111.274352 -334.040988) (xy 111.516668 -334.040988) (xy 111.516668 -333.962502) (xy 112.3061 -333.962502)
					(xy 112.3061 -333.644748) (xy 112.368076 -333.644748) (xy 112.368076 -332.966822) (xy 110.818676 -332.966822)
					(xy 110.818676 -333.423514) (xy 111.514382 -333.423514) (xy 111.514382 -333.262986) (xy 112.073182 -333.262986)
					(xy 112.073182 -333.669386) (xy 111.514382 -333.669386) (xy 111.514382 -333.448914) (xy 110.818676 -333.448914)
					(xy 110.818676 -333.575914) (xy 111.274352 -333.575914)
				)
			)
		)
	)
	(footprint ""
		(layer "F.Cu")
		(at 356.54488 -294.01008)
		(property "Reference" "C217"
			(at 0 0 0)
			(layer "F.SilkS")
			(hide yes)
			(effects
				(font
					(size 1.27 1.27)
				)
			)
		)
		(property "Value" ""
			(at 0 0 0)
			(layer "F.Fab")
			(effects
				(font
					(size 1.27 1.27)
				)
			)
		)
		(duplicate_pad_numbers_are_jumpers no)
		(fp_line
			(start -1.524 -0.762)
			(end 1.524 -0.762)
			(stroke
				(width 0.1524)
				(type default)
			)
			(layer "F.SilkS")
		)
		(fp_line
			(start -1.524 0.762)
			(end -1.524 -0.762)
			(stroke
				(width 0.1524)
				(type default)
			)
			(layer "F.SilkS")
		)
		(fp_line
			(start 1.524 -0.762)
			(end 1.524 0.762)
			(stroke
				(width 0.1524)
				(type default)
			)
			(layer "F.SilkS")
		)
		(fp_line
			(start 1.524 0.762)
			(end -1.524 0.762)
			(stroke
				(width 0.1524)
				(type default)
			)
			(layer "F.SilkS")
		)
		(fp_line
			(start -1.1049 -0.724916)
			(end -1.1049 0.724916)
			(stroke
				(width 0.1)
				(type default)
			)
			(layer "F.Fab")
		)
		(fp_line
			(start -1.1049 0.724916)
			(end 1.1049 0.724916)
			(stroke
				(width 0.1)
				(type default)
			)
			(layer "F.Fab")
		)
		(fp_line
			(start 1.1049 -0.724916)
			(end -1.1049 -0.724916)
			(stroke
				(width 0.1)
				(type default)
			)
			(layer "F.Fab")
		)
		(fp_line
			(start 1.1049 0.724916)
			(end 1.1049 -0.724916)
			(stroke
				(width 0.1)
				(type default)
			)
			(layer "F.Fab")
		)
		(pad "1" smd rect
			(at -0.889 0 180)
			(size 1.016 1.27)
			(layers "F.Cu" "F.Mask" "F.Paste")
			(net "PVCCIN_CPU0")
		)
		(pad "2" smd rect
			(at 0.889 0 180)
			(size 1.016 1.27)
			(layers "F.Cu" "F.Mask" "F.Paste")
			(net "GND")
		)
	)
)
